(kicad_pcb
	(version 20260206)
	(generator "pcbnew")
	(generator_version "10.0")
	(general
		(thickness 1.6)
		(legacy_teardrops no)
	)
	(paper "A4")
	(title_block
		(title "04192023_DAF0TMB3IC0_F0TG_MB_C_brd_V02_OCP.brd")
		(comment 1 "Grand Teton / footprints 7054-7060 of 8354")
	)
	(layers
		(0 "F.Cu" signal "TOP")
		(4 "In1.Cu" signal "GND")
		(6 "In2.Cu" signal "IN1")
		(8 "In3.Cu" signal "GND1")
		(10 "In4.Cu" signal "IN2")
		(12 "In5.Cu" signal "GND2")
		(14 "In6.Cu" signal "IN3")
		(16 "In7.Cu" signal "GND3")
		(18 "In8.Cu" signal "VCC")
		(20 "In9.Cu" signal "VCC1")
		(22 "In10.Cu" signal "GND4")
		(24 "In11.Cu" signal "IN4")
		(26 "In12.Cu" signal "GND5")
		(28 "In13.Cu" signal "IN5")
		(30 "In14.Cu" signal "GND6")
		(32 "In15.Cu" signal "IN6")
		(34 "In16.Cu" signal "GND7")
		(2 "B.Cu" signal "BOTTOM")
		(9 "F.Adhes" user "F.Adhesive")
		(11 "B.Adhes" user "B.Adhesive")
		(13 "F.Paste" user "Package Geometry/Pastemask Top")
		(15 "B.Paste" user "Package Geometry/Pastemask Bottom")
		(5 "F.SilkS" user "Ref Des/Silkscreen Top")
		(7 "B.SilkS" user "Ref Des/Silkscreen Bottom")
		(1 "F.Mask" user "Board Geometry/Soldermask Top")
		(3 "B.Mask" user "Board Geometry/Soldermask Bottom")
		(17 "Dwgs.User" user "User.Drawings")
		(19 "Cmts.User" user "User.Comments")
		(21 "Eco1.User" user "User.Eco1")
		(23 "Eco2.User" user "User.Eco2")
		(25 "Edge.Cuts" user "Board Geometry/Outline")
		(27 "Margin" user)
		(31 "F.CrtYd" user "Package Geometry/Place Bound Top")
		(29 "B.CrtYd" user "Package Geometry/Place Bound Bottom")
		(35 "F.Fab" user "Ref Des/Assembly Top")
		(33 "B.Fab" user "Ref Des/Assembly Bottom")
	)
	(footprint ""
		(layer "B.Cu")
		(at 154.577288 -9.48055 90)
		(property "Reference" "R6068"
			(at 0 0 90)
			(layer "B.SilkS")
			(hide yes)
			(effects
				(font
					(size 1.27 1.27)
				)
				(justify mirror)
			)
		)
		(property "Value" ""
			(at 0 0 90)
			(layer "B.Fab")
			(effects
				(font
					(size 1.27 1.27)
				)
				(justify mirror)
			)
		)
		(duplicate_pad_numbers_are_jumpers no)
		(fp_line
			(start 0.7874 -0.4064)
			(end -0.7874 -0.4064)
			(stroke
				(width 0.1524)
				(type default)
			)
			(layer "B.SilkS")
		)
		(fp_line
			(start -0.7874 -0.4064)
			(end -0.7874 0.4064)
			(stroke
				(width 0.1524)
				(type default)
			)
			(layer "B.SilkS")
		)
		(fp_line
			(start 0.7874 0.4064)
			(end 0.7874 -0.4064)
			(stroke
				(width 0.1524)
				(type default)
			)
			(layer "B.SilkS")
		)
		(fp_line
			(start -0.7874 0.4064)
			(end 0.7874 0.4064)
			(stroke
				(width 0.1524)
				(type default)
			)
			(layer "B.SilkS")
		)
		(fp_line
			(start 0.67945 -0.305054)
			(end 0.12065 -0.305054)
			(stroke
				(width 0.1)
				(type default)
			)
			(layer "B.Fab")
		)
		(fp_line
			(start 0.12065 -0.305054)
			(end 0.12065 -0.2794)
			(stroke
				(width 0.1)
				(type default)
			)
			(layer "B.Fab")
		)
		(fp_line
			(start -0.12065 -0.3048)
			(end -0.67945 -0.3048)
			(stroke
				(width 0.1)
				(type default)
			)
			(layer "B.Fab")
		)
		(fp_line
			(start -0.67945 -0.3048)
			(end -0.67945 0.3048)
			(stroke
				(width 0.1)
				(type default)
			)
			(layer "B.Fab")
		)
		(fp_line
			(start 0.12065 -0.2794)
			(end -0.12065 -0.2794)
			(stroke
				(width 0.1)
				(type default)
			)
			(layer "B.Fab")
		)
		(fp_line
			(start -0.12065 -0.2794)
			(end -0.12065 -0.3048)
			(stroke
				(width 0.1)
				(type default)
			)
			(layer "B.Fab")
		)
		(fp_line
			(start 0.12065 0.2794)
			(end 0.12065 0.3048)
			(stroke
				(width 0.1)
				(type default)
			)
			(layer "B.Fab")
		)
		(fp_line
			(start -0.120396 0.2794)
			(end 0.12065 0.2794)
			(stroke
				(width 0.1)
				(type default)
			)
			(layer "B.Fab")
		)
		(fp_line
			(start 0.67945 0.3048)
			(end 0.67945 -0.305054)
			(stroke
				(width 0.1)
				(type default)
			)
			(layer "B.Fab")
		)
		(fp_line
			(start 0.12065 0.3048)
			(end 0.67945 0.3048)
			(stroke
				(width 0.1)
				(type default)
			)
			(layer "B.Fab")
		)
		(fp_line
			(start -0.120396 0.3048)
			(end -0.120396 0.2794)
			(stroke
				(width 0.1)
				(type default)
			)
			(layer "B.Fab")
		)
		(fp_line
			(start -0.67945 0.3048)
			(end -0.120396 0.3048)
			(stroke
				(width 0.1)
				(type default)
			)
			(layer "B.Fab")
		)
		(pad "1" smd rect
			(at 0.40005 0 90)
			(size 0.4572 0.508)
			(layers "B.Cu" "B.Mask" "B.Paste")
			(net "JTAG_SCM_TDO_R")
		)
		(pad "2" smd rect
			(at -0.40005 0 90)
			(size 0.4572 0.508)
			(layers "B.Cu" "B.Mask" "B.Paste")
			(net "JTAG_SCM_TDO")
		)
	)
	(footprint ""
		(layer "B.Cu")
		(at 102.73538 -180.027834 90)
		(property "Reference" "PR199"
			(at 0 0 90)
			(layer "B.SilkS")
			(hide yes)
			(effects
				(font
					(size 1.27 1.27)
				)
				(justify mirror)
			)
		)
		(property "Value" ""
			(at 0 0 90)
			(layer "B.Fab")
			(effects
				(font
					(size 1.27 1.27)
				)
				(justify mirror)
			)
		)
		(duplicate_pad_numbers_are_jumpers no)
		(fp_line
			(start 0.7874 -0.4064)
			(end -0.7874 -0.4064)
			(stroke
				(width 0.1524)
				(type default)
			)
			(layer "B.SilkS")
		)
		(fp_line
			(start -0.7874 -0.4064)
			(end -0.7874 0.4064)
			(stroke
				(width 0.1524)
				(type default)
			)
			(layer "B.SilkS")
		)
		(fp_line
			(start 0.7874 0.4064)
			(end 0.7874 -0.4064)
			(stroke
				(width 0.1524)
				(type default)
			)
			(layer "B.SilkS")
		)
		(fp_line
			(start -0.7874 0.4064)
			(end 0.7874 0.4064)
			(stroke
				(width 0.1524)
				(type default)
			)
			(layer "B.SilkS")
		)
		(fp_line
			(start 0.67945 -0.305054)
			(end 0.12065 -0.305054)
			(stroke
				(width 0.1)
				(type default)
			)
			(layer "B.Fab")
		)
		(fp_line
			(start 0.12065 -0.305054)
			(end 0.12065 -0.2794)
			(stroke
				(width 0.1)
				(type default)
			)
			(layer "B.Fab")
		)
		(fp_line
			(start -0.12065 -0.3048)
			(end -0.67945 -0.3048)
			(stroke
				(width 0.1)
				(type default)
			)
			(layer "B.Fab")
		)
		(fp_line
			(start -0.67945 -0.3048)
			(end -0.67945 0.3048)
			(stroke
				(width 0.1)
				(type default)
			)
			(layer "B.Fab")
		)
		(fp_line
			(start 0.12065 -0.2794)
			(end -0.12065 -0.2794)
			(stroke
				(width 0.1)
				(type default)
			)
			(layer "B.Fab")
		)
		(fp_line
			(start -0.12065 -0.2794)
			(end -0.12065 -0.3048)
			(stroke
				(width 0.1)
				(type default)
			)
			(layer "B.Fab")
		)
		(fp_line
			(start 0.12065 0.2794)
			(end 0.12065 0.3048)
			(stroke
				(width 0.1)
				(type default)
			)
			(layer "B.Fab")
		)
		(fp_line
			(start -0.120396 0.2794)
			(end 0.12065 0.2794)
			(stroke
				(width 0.1)
				(type default)
			)
			(layer "B.Fab")
		)
		(fp_line
			(start 0.67945 0.3048)
			(end 0.67945 -0.305054)
			(stroke
				(width 0.1)
				(type default)
			)
			(layer "B.Fab")
		)
		(fp_line
			(start 0.12065 0.3048)
			(end 0.67945 0.3048)
			(stroke
				(width 0.1)
				(type default)
			)
			(layer "B.Fab")
		)
		(fp_line
			(start -0.120396 0.3048)
			(end -0.120396 0.2794)
			(stroke
				(width 0.1)
				(type default)
			)
			(layer "B.Fab")
		)
		(fp_line
			(start -0.67945 0.3048)
			(end -0.120396 0.3048)
			(stroke
				(width 0.1)
				(type default)
			)
			(layer "B.Fab")
		)
		(pad "1" smd circle
			(at 0.40005 0 270)
			(size 0 0)
			(layers "B.Cu" "B.Mask" "B.Paste")
			(net "PVDDCR_CPU0_P1_VOS3")
		)
		(pad "2" smd circle
			(at -0.40005 0 270)
			(size 0 0)
			(layers "B.Cu" "B.Mask" "B.Paste")
			(net "PVDDCR_CPU0_P1")
		)
	)
	(footprint ""
		(layer "B.Cu")
		(at 53.378608 -386.766562 90)
		(property "Reference" "C139"
			(at 0 0 90)
			(layer "B.SilkS")
			(hide yes)
			(effects
				(font
					(size 1.27 1.27)
				)
				(justify mirror)
			)
		)
		(property "Value" ""
			(at 0 0 90)
			(layer "B.Fab")
			(effects
				(font
					(size 1.27 1.27)
				)
				(justify mirror)
			)
		)
		(duplicate_pad_numbers_are_jumpers no)
		(fp_line
			(start 0.299974 -0.150114)
			(end -0.299974 -0.150114)
			(stroke
				(width 0.1)
				(type default)
			)
			(layer "B.Fab")
		)
		(fp_line
			(start -0.299974 -0.150114)
			(end -0.299974 0.150114)
			(stroke
				(width 0.1)
				(type default)
			)
			(layer "B.Fab")
		)
		(fp_line
			(start 0.299974 0.150114)
			(end 0.299974 -0.150114)
			(stroke
				(width 0.1)
				(type default)
			)
			(layer "B.Fab")
		)
		(fp_line
			(start -0.299974 0.150114)
			(end 0.299974 0.150114)
			(stroke
				(width 0.1)
				(type default)
			)
			(layer "B.Fab")
		)
		(pad "1" smd rect
			(at 0.2667 0 270)
			(size 0.3048 0.381)
			(layers "B.Cu" "B.Mask" "B.Paste")
			(net "P0V9_CPU1_RT_2D")
		)
		(pad "2" smd rect
			(at -0.2667 0 270)
			(size 0.3048 0.381)
			(layers "B.Cu" "B.Mask" "B.Paste")
			(net "GND")
		)
	)
	(footprint ""
		(layer "B.Cu")
		(at 365.835692 -259.355082)
		(property "Reference" "C2552"
			(at 0 0 0)
			(layer "B.SilkS")
			(hide yes)
			(effects
				(font
					(size 1.27 1.27)
				)
				(justify mirror)
			)
		)
		(property "Value" ""
			(at 0 0 0)
			(layer "B.Fab")
			(effects
				(font
					(size 1.27 1.27)
				)
				(justify mirror)
			)
		)
		(duplicate_pad_numbers_are_jumpers no)
		(fp_line
			(start -0.7874 -0.4064)
			(end -0.7874 0.4064)
			(stroke
				(width 0.1524)
				(type default)
			)
			(layer "B.SilkS")
		)
		(fp_line
			(start -0.7874 0.4064)
			(end 0.7874 0.4064)
			(stroke
				(width 0.1524)
				(type default)
			)
			(layer "B.SilkS")
		)
		(fp_line
			(start 0.7874 -0.4064)
			(end -0.7874 -0.4064)
			(stroke
				(width 0.1524)
				(type default)
			)
			(layer "B.SilkS")
		)
		(fp_line
			(start 0.7874 0.4064)
			(end 0.7874 -0.4064)
			(stroke
				(width 0.1524)
				(type default)
			)
			(layer "B.SilkS")
		)
		(fp_line
			(start -0.67945 -0.3048)
			(end -0.67945 0.3048)
			(stroke
				(width 0.1)
				(type default)
			)
			(layer "B.Fab")
		)
		(fp_line
			(start -0.67945 0.3048)
			(end -0.120396 0.3048)
			(stroke
				(width 0.1)
				(type default)
			)
			(layer "B.Fab")
		)
		(fp_line
			(start -0.12065 -0.3048)
			(end -0.67945 -0.3048)
			(stroke
				(width 0.1)
				(type default)
			)
			(layer "B.Fab")
		)
		(fp_line
			(start -0.12065 -0.2794)
			(end -0.12065 -0.3048)
			(stroke
				(width 0.1)
				(type default)
			)
			(layer "B.Fab")
		)
		(fp_line
			(start -0.120396 0.2794)
			(end 0.12065 0.2794)
			(stroke
				(width 0.1)
				(type default)
			)
			(layer "B.Fab")
		)
		(fp_line
			(start -0.120396 0.3048)
			(end -0.120396 0.2794)
			(stroke
				(width 0.1)
				(type default)
			)
			(layer "B.Fab")
		)
		(fp_line
			(start 0.12065 -0.305054)
			(end 0.12065 -0.2794)
			(stroke
				(width 0.1)
				(type default)
			)
			(layer "B.Fab")
		)
		(fp_line
			(start 0.12065 -0.2794)
			(end -0.12065 -0.2794)
			(stroke
				(width 0.1)
				(type default)
			)
			(layer "B.Fab")
		)
		(fp_line
			(start 0.12065 0.2794)
			(end 0.12065 0.3048)
			(stroke
				(width 0.1)
				(type default)
			)
			(layer "B.Fab")
		)
		(fp_line
			(start 0.12065 0.3048)
			(end 0.67945 0.3048)
			(stroke
				(width 0.1)
				(type default)
			)
			(layer "B.Fab")
		)
		(fp_line
			(start 0.67945 -0.305054)
			(end 0.12065 -0.305054)
			(stroke
				(width 0.1)
				(type default)
			)
			(layer "B.Fab")
		)
		(fp_line
			(start 0.67945 0.3048)
			(end 0.67945 -0.305054)
			(stroke
				(width 0.1)
				(type default)
			)
			(layer "B.Fab")
		)
		(pad "1" smd circle
			(at 0.40005 0 180)
			(size 0 0)
			(layers "B.Cu" "B.Mask" "B.Paste")
			(net "PVDDCR_SOC_P0")
		)
		(pad "2" smd circle
			(at -0.40005 0 180)
			(size 0 0)
			(layers "B.Cu" "B.Mask" "B.Paste")
			(net "GND")
		)
	)
	(footprint ""
		(layer "B.Cu")
		(at 438.344564 -195.859146 180)
		(property "Reference" "R1684"
			(at 0 0 0)
			(layer "B.SilkS")
			(hide yes)
			(effects
				(font
					(size 1.27 1.27)
				)
				(justify mirror)
			)
		)
		(property "Value" ""
			(at 0 0 0)
			(layer "B.Fab")
			(effects
				(font
					(size 1.27 1.27)
				)
				(justify mirror)
			)
		)
		(duplicate_pad_numbers_are_jumpers no)
		(fp_line
			(start 0.7874 0.4064)
			(end 0.7874 -0.4064)
			(stroke
				(width 0.1524)
				(type default)
			)
			(layer "B.SilkS")
		)
		(fp_line
			(start 0.7874 -0.4064)
			(end -0.7874 -0.4064)
			(stroke
				(width 0.1524)
				(type default)
			)
			(layer "B.SilkS")
		)
		(fp_line
			(start -0.7874 0.4064)
			(end 0.7874 0.4064)
			(stroke
				(width 0.1524)
				(type default)
			)
			(layer "B.SilkS")
		)
		(fp_line
			(start -0.7874 -0.4064)
			(end -0.7874 0.4064)
			(stroke
				(width 0.1524)
				(type default)
			)
			(layer "B.SilkS")
		)
		(fp_line
			(start 0.67945 0.3048)
			(end 0.67945 -0.305054)
			(stroke
				(width 0.1)
				(type default)
			)
			(layer "B.Fab")
		)
		(fp_line
			(start 0.67945 -0.305054)
			(end 0.12065 -0.305054)
			(stroke
				(width 0.1)
				(type default)
			)
			(layer "B.Fab")
		)
		(fp_line
			(start 0.12065 0.3048)
			(end 0.67945 0.3048)
			(stroke
				(width 0.1)
				(type default)
			)
			(layer "B.Fab")
		)
		(fp_line
			(start 0.12065 0.2794)
			(end 0.12065 0.3048)
			(stroke
				(width 0.1)
				(type default)
			)
			(layer "B.Fab")
		)
		(fp_line
			(start 0.12065 -0.2794)
			(end -0.12065 -0.2794)
			(stroke
				(width 0.1)
				(type default)
			)
			(layer "B.Fab")
		)
		(fp_line
			(start 0.12065 -0.305054)
			(end 0.12065 -0.2794)
			(stroke
				(width 0.1)
				(type default)
			)
			(layer "B.Fab")
		)
		(fp_line
			(start -0.120396 0.3048)
			(end -0.120396 0.2794)
			(stroke
				(width 0.1)
				(type default)
			)
			(layer "B.Fab")
		)
		(fp_line
			(start -0.120396 0.2794)
			(end 0.12065 0.2794)
			(stroke
				(width 0.1)
				(type default)
			)
			(layer "B.Fab")
		)
		(fp_line
			(start -0.12065 -0.2794)
			(end -0.12065 -0.3048)
			(stroke
				(width 0.1)
				(type default)
			)
			(layer "B.Fab")
		)
		(fp_line
			(start -0.12065 -0.3048)
			(end -0.67945 -0.3048)
			(stroke
				(width 0.1)
				(type default)
			)
			(layer "B.Fab")
		)
		(fp_line
			(start -0.67945 0.3048)
			(end -0.120396 0.3048)
			(stroke
				(width 0.1)
				(type default)
			)
			(layer "B.Fab")
		)
		(fp_line
			(start -0.67945 -0.3048)
			(end -0.67945 0.3048)
			(stroke
				(width 0.1)
				(type default)
			)
			(layer "B.Fab")
		)
		(pad "1" smd circle
			(at 0.40005 0)
			(size 0 0)
			(layers "B.Cu" "B.Mask" "B.Paste")
			(net "I3C_SPD_DDRGL_CPU0_SDA")
		)
		(pad "2" smd circle
			(at -0.40005 0)
			(size 0 0)
			(layers "B.Cu" "B.Mask" "B.Paste")
			(net "I3C_SPD_DDRJ_CPU0_SDA")
		)
	)
	(footprint ""
		(layer "B.Cu")
		(at 231.8512 -327.21169 180)
		(property "Reference" "R1248"
			(at 0 0 0)
			(layer "B.SilkS")
			(hide yes)
			(effects
				(font
					(size 1.27 1.27)
				)
				(justify mirror)
			)
		)
		(property "Value" ""
			(at 0 0 0)
			(layer "B.Fab")
			(effects
				(font
					(size 1.27 1.27)
				)
				(justify mirror)
			)
		)
		(duplicate_pad_numbers_are_jumpers no)
		(fp_line
			(start 0.7874 0.4064)
			(end 0.7874 -0.4064)
			(stroke
				(width 0.1524)
				(type default)
			)
			(layer "B.SilkS")
		)
		(fp_line
			(start 0.7874 -0.4064)
			(end -0.7874 -0.4064)
			(stroke
				(width 0.1524)
				(type default)
			)
			(layer "B.SilkS")
		)
		(fp_line
			(start -0.7874 0.4064)
			(end 0.7874 0.4064)
			(stroke
				(width 0.1524)
				(type default)
			)
			(layer "B.SilkS")
		)
		(fp_line
			(start -0.7874 -0.4064)
			(end -0.7874 0.4064)
			(stroke
				(width 0.1524)
				(type default)
			)
			(layer "B.SilkS")
		)
		(fp_line
			(start 0.67945 0.3048)
			(end 0.67945 -0.305054)
			(stroke
				(width 0.1)
				(type default)
			)
			(layer "B.Fab")
		)
		(fp_line
			(start 0.67945 -0.305054)
			(end 0.12065 -0.305054)
			(stroke
				(width 0.1)
				(type default)
			)
			(layer "B.Fab")
		)
		(fp_line
			(start 0.12065 0.3048)
			(end 0.67945 0.3048)
			(stroke
				(width 0.1)
				(type default)
			)
			(layer "B.Fab")
		)
		(fp_line
			(start 0.12065 0.2794)
			(end 0.12065 0.3048)
			(stroke
				(width 0.1)
				(type default)
			)
			(layer "B.Fab")
		)
		(fp_line
			(start 0.12065 -0.2794)
			(end -0.12065 -0.2794)
			(stroke
				(width 0.1)
				(type default)
			)
			(layer "B.Fab")
		)
		(fp_line
			(start 0.12065 -0.305054)
			(end 0.12065 -0.2794)
			(stroke
				(width 0.1)
				(type default)
			)
			(layer "B.Fab")
		)
		(fp_line
			(start -0.120396 0.3048)
			(end -0.120396 0.2794)
			(stroke
				(width 0.1)
				(type default)
			)
			(layer "B.Fab")
		)
		(fp_line
			(start -0.120396 0.2794)
			(end 0.12065 0.2794)
			(stroke
				(width 0.1)
				(type default)
			)
			(layer "B.Fab")
		)
		(fp_line
			(start -0.12065 -0.2794)
			(end -0.12065 -0.3048)
			(stroke
				(width 0.1)
				(type default)
			)
			(layer "B.Fab")
		)
		(fp_line
			(start -0.12065 -0.3048)
			(end -0.67945 -0.3048)
			(stroke
				(width 0.1)
				(type default)
			)
			(layer "B.Fab")
		)
		(fp_line
			(start -0.67945 0.3048)
			(end -0.120396 0.3048)
			(stroke
				(width 0.1)
				(type default)
			)
			(layer "B.Fab")
		)
		(fp_line
			(start -0.67945 -0.3048)
			(end -0.67945 0.3048)
			(stroke
				(width 0.1)
				(type default)
			)
			(layer "B.Fab")
		)
		(pad "1" smd rect
			(at 0.40005 0 180)
			(size 0.4572 0.508)
			(layers "B.Cu" "B.Mask" "B.Paste")
			(net "PVDD_33_S5_ADC")
		)
		(pad "2" smd rect
			(at -0.40005 0 180)
			(size 0.4572 0.508)
			(layers "B.Cu" "B.Mask" "B.Paste")
			(net "PVDD_33_S5_ADC_MAM")
		)
	)
	(footprint ""
		(layer "B.Cu")
		(at 368.701828 -390.078722)
		(property "Reference" "C7019"
			(at 0 0 0)
			(layer "B.SilkS")
			(hide yes)
			(effects
				(font
					(size 1.27 1.27)
				)
				(justify mirror)
			)
		)
		(property "Value" ""
			(at 0 0 0)
			(layer "B.Fab")
			(effects
				(font
					(size 1.27 1.27)
				)
				(justify mirror)
			)
		)
		(duplicate_pad_numbers_are_jumpers no)
		(fp_line
			(start -1.524 -0.762)
			(end -1.524 0.762)
			(stroke
				(width 0.1524)
				(type default)
			)
			(layer "B.SilkS")
		)
		(fp_line
			(start -1.524 0.762)
			(end 1.524 0.762)
			(stroke
				(width 0.1524)
				(type default)
			)
			(layer "B.SilkS")
		)
		(fp_line
			(start 1.524 -0.762)
			(end -1.524 -0.762)
			(stroke
				(width 0.1524)
				(type default)
			)
			(layer "B.SilkS")
		)
		(fp_line
			(start 1.524 0.762)
			(end 1.524 -0.762)
			(stroke
				(width 0.1524)
				(type default)
			)
			(layer "B.SilkS")
		)
		(fp_line
			(start -1.1049 -0.724916)
			(end 1.1049 -0.724916)
			(stroke
				(width 0.1)
				(type default)
			)
			(layer "B.Fab")
		)
		(fp_line
			(start -1.1049 0.724916)
			(end -1.1049 -0.724916)
			(stroke
				(width 0.1)
				(type default)
			)
			(layer "B.Fab")
		)
		(fp_line
			(start 1.1049 -0.724916)
			(end 1.1049 0.724916)
			(stroke
				(width 0.1)
				(type default)
			)
			(layer "B.Fab")
		)
		(fp_line
			(start 1.1049 0.724916)
			(end -1.1049 0.724916)
			(stroke
				(width 0.1)
				(type default)
			)
			(layer "B.Fab")
		)
		(pad "1" smd rect
			(at 0.889 0)
			(size 1.016 1.27)
			(layers "B.Cu" "B.Mask" "B.Paste")
			(net "P0V9_CPU0_RT3_2A")
		)
		(pad "2" smd rect
			(at -0.889 0)
			(size 1.016 1.27)
			(layers "B.Cu" "B.Mask" "B.Paste")
			(net "GND")
		)
	)
)
